# S9S_MB_2U (Grand Teton) — schematic netlist excerpt (pin names and nets, part order shuffled) for the footprints in the layout excerpt that follows; sources: Cadence DE-HDL packaged netlist, KiCad conversion of 03242023_DA0F0TMBIJ0_F0T_Motherboard_J_brd_V01_OCP.brd

R2557  Q_RES  0 5% CHIP  pkg 0402LF  page 296 : A = IRQ_PVCCD_CPU1_VRHOT_LVC3_R_N ; B = IRQ_PVCCD_CPU1_VRHOT_LVC3_N
R4086  Q_RES  10K 1% CHIP  pkg 0402LF  page 215 : A = P3V3_AUX_FPGA_VCCIO2 ; B = PULL_FPGA_PB46A
PC1204  Q_CAPP  560UF 2.5V 20% OSCON  pkg THLF  page 290 : A = PVCCFA_EHV_FIVRA_CPU1 ; B = GND

(kicad_pcb
	(version 20260206)
	(generator "pcbnew")
	(generator_version "10.0")
	(general
		(thickness 1.6)
		(legacy_teardrops no)
	)
	(paper "A4")
	(title_block
		(title "03242023_DA0F0TMBIJ0_F0T_Motherboard_J_brd_V01_OCP.brd")
		(comment 1 "Grand Teton / footprints 1852-1854 of 6105")
	)
	(layers
		(0 "F.Cu" signal "TOP")
		(4 "In1.Cu" signal "GND")
		(6 "In2.Cu" signal "IN1")
		(8 "In3.Cu" signal "GND1")
		(10 "In4.Cu" signal "IN2")
		(12 "In5.Cu" signal "GND2")
		(14 "In6.Cu" signal "IN3")
		(16 "In7.Cu" signal "GND3")
		(18 "In8.Cu" signal "VCC")
		(20 "In9.Cu" signal "VCC1")
		(22 "In10.Cu" signal "GND4")
		(24 "In11.Cu" signal "IN4")
		(26 "In12.Cu" signal "GND5")
		(28 "In13.Cu" signal "IN5")
		(30 "In14.Cu" signal "GND6")
		(32 "In15.Cu" signal "IN6")
		(34 "In16.Cu" signal "GND7")
		(2 "B.Cu" signal "BOTTOM")
		(9 "F.Adhes" user "F.Adhesive")
		(11 "B.Adhes" user "B.Adhesive")
		(13 "F.Paste" user "Package Geometry/Pastemask Top")
		(15 "B.Paste" user "Package Geometry/Pastemask Bottom")
		(5 "F.SilkS" user "Ref Des/Silkscreen Top")
		(7 "B.SilkS" user "Ref Des/Silkscreen Bottom")
		(1 "F.Mask" user "Board Geometry/Soldermask Top")
		(3 "B.Mask" user "Board Geometry/Soldermask Bottom")
		(17 "Dwgs.User" user "User.Drawings")
		(19 "Cmts.User" user "User.Comments")
		(21 "Eco1.User" user "User.Eco1")
		(23 "Eco2.User" user "User.Eco2")
		(25 "Edge.Cuts" user "Board Geometry/Outline")
		(27 "Margin" user)
		(31 "F.CrtYd" user "Package Geometry/Place Bound Top")
		(29 "B.CrtYd" user "Package Geometry/Place Bound Bottom")
		(35 "F.Fab" user "Ref Des/Assembly Top")
		(33 "B.Fab" user "Ref Des/Assembly Bottom")
	)
	(footprint ""
		(layer "F.Cu")
		(at 193.3956 -125.336808 180)
		(property "Reference" "R4086"
			(at 0 0 180)
			(layer "F.SilkS")
			(hide yes)
			(effects
				(font
					(size 1.27 1.27)
				)
			)
		)
		(property "Value" ""
			(at 0 0 180)
			(layer "F.Fab")
			(effects
				(font
					(size 1.27 1.27)
				)
			)
		)
		(duplicate_pad_numbers_are_jumpers no)
		(fp_line
			(start 0.7874 0.4064)
			(end -0.7874 0.4064)
			(stroke
				(width 0.1524)
				(type default)
			)
			(layer "F.SilkS")
		)
		(fp_line
			(start 0.7874 -0.4064)
			(end 0.7874 0.4064)
			(stroke
				(width 0.1524)
				(type default)
			)
			(layer "F.SilkS")
		)
		(fp_line
			(start -0.7874 0.4064)
			(end -0.7874 -0.4064)
			(stroke
				(width 0.1524)
				(type default)
			)
			(layer "F.SilkS")
		)
		(fp_line
			(start -0.7874 -0.4064)
			(end 0.7874 -0.4064)
			(stroke
				(width 0.1524)
				(type default)
			)
			(layer "F.SilkS")
		)
		(fp_line
			(start 0.67945 0.3048)
			(end 0.120396 0.3048)
			(stroke
				(width 0.1)
				(type default)
			)
			(layer "F.Fab")
		)
		(fp_line
			(start 0.67945 -0.3048)
			(end 0.67945 0.3048)
			(stroke
				(width 0.1)
				(type default)
			)
			(layer "F.Fab")
		)
		(fp_line
			(start 0.12065 -0.2794)
			(end 0.12065 -0.3048)
			(stroke
				(width 0.1)
				(type default)
			)
			(layer "F.Fab")
		)
		(fp_line
			(start 0.12065 -0.3048)
			(end 0.67945 -0.3048)
			(stroke
				(width 0.1)
				(type default)
			)
			(layer "F.Fab")
		)
		(fp_line
			(start 0.120396 0.3048)
			(end 0.120396 0.2794)
			(stroke
				(width 0.1)
				(type default)
			)
			(layer "F.Fab")
		)
		(fp_line
			(start 0.120396 0.2794)
			(end -0.12065 0.2794)
			(stroke
				(width 0.1)
				(type default)
			)
			(layer "F.Fab")
		)
		(fp_line
			(start -0.12065 0.3048)
			(end -0.67945 0.3048)
			(stroke
				(width 0.1)
				(type default)
			)
			(layer "F.Fab")
		)
		(fp_line
			(start -0.12065 0.2794)
			(end -0.12065 0.3048)
			(stroke
				(width 0.1)
				(type default)
			)
			(layer "F.Fab")
		)
		(fp_line
			(start -0.12065 -0.2794)
			(end 0.12065 -0.2794)
			(stroke
				(width 0.1)
				(type default)
			)
			(layer "F.Fab")
		)
		(fp_line
			(start -0.12065 -0.305054)
			(end -0.12065 -0.2794)
			(stroke
				(width 0.1)
				(type default)
			)
			(layer "F.Fab")
		)
		(fp_line
			(start -0.67945 0.3048)
			(end -0.67945 -0.305054)
			(stroke
				(width 0.1)
				(type default)
			)
			(layer "F.Fab")
		)
		(fp_line
			(start -0.67945 -0.305054)
			(end -0.12065 -0.305054)
			(stroke
				(width 0.1)
				(type default)
			)
			(layer "F.Fab")
		)
		(pad "1" smd circle
			(at -0.40005 0 180)
			(size 0 0)
			(layers "F.Cu" "F.Mask" "F.Paste")
			(net "P3V3_AUX_FPGA_VCCIO2")
		)
		(pad "2" smd circle
			(at 0.40005 0 180)
			(size 0 0)
			(layers "F.Cu" "F.Mask" "F.Paste")
			(net "PULL_FPGA_PB46A")
		)
	)
	(footprint ""
		(layer "F.Cu")
		(at 22.723094 -168.181274 90)
		(property "Reference" "R2557"
			(at 0 0 90)
			(layer "F.SilkS")
			(hide yes)
			(effects
				(font
					(size 1.27 1.27)
				)
			)
		)
		(property "Value" ""
			(at 0 0 90)
			(layer "F.Fab")
			(effects
				(font
					(size 1.27 1.27)
				)
			)
		)
		(duplicate_pad_numbers_are_jumpers no)
		(fp_line
			(start 0.7874 -0.4064)
			(end 0.7874 0.4064)
			(stroke
				(width 0.1524)
				(type default)
			)
			(layer "F.SilkS")
		)
		(fp_line
			(start -0.7874 -0.4064)
			(end 0.7874 -0.4064)
			(stroke
				(width 0.1524)
				(type default)
			)
			(layer "F.SilkS")
		)
		(fp_line
			(start 0.7874 0.4064)
			(end -0.7874 0.4064)
			(stroke
				(width 0.1524)
				(type default)
			)
			(layer "F.SilkS")
		)
		(fp_line
			(start -0.7874 0.4064)
			(end -0.7874 -0.4064)
			(stroke
				(width 0.1524)
				(type default)
			)
			(layer "F.SilkS")
		)
		(fp_line
			(start -0.12065 -0.305054)
			(end -0.12065 -0.2794)
			(stroke
				(width 0.1)
				(type default)
			)
			(layer "F.Fab")
		)
		(fp_line
			(start -0.67945 -0.305054)
			(end -0.12065 -0.305054)
			(stroke
				(width 0.1)
				(type default)
			)
			(layer "F.Fab")
		)
		(fp_line
			(start 0.67945 -0.3048)
			(end 0.67945 0.3048)
			(stroke
				(width 0.1)
				(type default)
			)
			(layer "F.Fab")
		)
		(fp_line
			(start 0.12065 -0.3048)
			(end 0.67945 -0.3048)
			(stroke
				(width 0.1)
				(type default)
			)
			(layer "F.Fab")
		)
		(fp_line
			(start 0.12065 -0.2794)
			(end 0.12065 -0.3048)
			(stroke
				(width 0.1)
				(type default)
			)
			(layer "F.Fab")
		)
		(fp_line
			(start -0.12065 -0.2794)
			(end 0.12065 -0.2794)
			(stroke
				(width 0.1)
				(type default)
			)
			(layer "F.Fab")
		)
		(fp_line
			(start 0.120396 0.2794)
			(end -0.12065 0.2794)
			(stroke
				(width 0.1)
				(type default)
			)
			(layer "F.Fab")
		)
		(fp_line
			(start -0.12065 0.2794)
			(end -0.12065 0.3048)
			(stroke
				(width 0.1)
				(type default)
			)
			(layer "F.Fab")
		)
		(fp_line
			(start 0.67945 0.3048)
			(end 0.120396 0.3048)
			(stroke
				(width 0.1)
				(type default)
			)
			(layer "F.Fab")
		)
		(fp_line
			(start 0.120396 0.3048)
			(end 0.120396 0.2794)
			(stroke
				(width 0.1)
				(type default)
			)
			(layer "F.Fab")
		)
		(fp_line
			(start -0.12065 0.3048)
			(end -0.67945 0.3048)
			(stroke
				(width 0.1)
				(type default)
			)
			(layer "F.Fab")
		)
		(fp_line
			(start -0.67945 0.3048)
			(end -0.67945 -0.305054)
			(stroke
				(width 0.1)
				(type default)
			)
			(layer "F.Fab")
		)
		(pad "1" smd circle
			(at -0.40005 0 90)
			(size 0 0)
			(layers "F.Cu" "F.Mask" "F.Paste")
			(net "IRQ_PVCCD_CPU1_VRHOT_LVC3_R_N")
		)
		(pad "2" smd circle
			(at 0.40005 0 90)
			(size 0 0)
			(layers "F.Cu" "F.Mask" "F.Paste")
			(net "IRQ_PVCCD_CPU1_VRHOT_LVC3_N")
		)
	)
	(footprint ""
		(layer "F.Cu")
		(at 177.156364 -337.483958)
		(property "Reference" "PC1204"
			(at 0 0 0)
			(layer "F.SilkS")
			(hide yes)
			(effects
				(font
					(size 1.27 1.27)
				)
			)
		)
		(property "Value" ""
			(at 0 0 0)
			(layer "F.Fab")
			(effects
				(font
					(size 1.27 1.27)
				)
			)
		)
		(duplicate_pad_numbers_are_jumpers no)
		(fp_line
			(start 2.750058 0.999998)
			(end -2.750058 0.999998)
			(stroke
				(width 0.1524)
				(type default)
			)
			(layer "F.SilkS")
		)
		(fp_circle
			(center 0 0.999998)
			(end 2.750058 0.999998)
			(stroke
				(width 0.1524)
				(type default)
			)
			(fill no)
			(layer "F.SilkS")
		)
		(fp_poly
			(pts
				(arc
					(start 2.750058 0.999998)
					(mid 0 3.750056)
					(end -2.750058 0.999998)
				)
			)
			(stroke
				(width 0)
				(type default)
			)
			(fill yes)
			(layer "F.SilkS")
		)
		(fp_circle
			(center 0 0.999998)
			(end 2.750058 0.999998)
			(stroke
				(width 0.1)
				(type default)
			)
			(fill no)
			(layer "F.Fab")
		)
		(pad "1" thru_hole rect
			(at 0 0)
			(size 1.5748 1.5748)
			(drill 1.0668)
			(layers "*.Cu" "*.Mask")
			(remove_unused_layers no)
			(net "PVCCFA_EHV_FIVRA_CPU1")
			(clearance 0)
			(padstack
				(mode front_inner_back)
				(layer "Inner"
					(shape circle)
					(size 1.5748 1.5748)
					(clearance 0)
				)
				(layer "B.Cu"
					(shape rect)
					(size 1.5748 1.5748)
					(clearance 0)
				)
			)
		)
		(pad "2" thru_hole circle
			(at 0 1.999996)
			(size 1.5748 1.5748)
			(drill 1.0668)
			(layers "*.Cu" "*.Mask")
			(remove_unused_layers no)
			(net "GND")
			(clearance 0)
		)
	)
)
